(kicad_pcb
	(version 20260206)
	(generator "pcbnew")
	(generator_version "10.0")
	(general
		(thickness 1.6)
		(legacy_teardrops no)
	)
	(paper "A4")
	(title_block
		(title "Wiwynn_Tioga_Pass_MB.brd")
		(comment 1 "Tioga Pass / footprints 286-293 of 4770")
	)
	(layers
		(0 "F.Cu" signal "TOP")
		(4 "In1.Cu" signal "L2GND")
		(6 "In2.Cu" signal "L3")
		(8 "In3.Cu" signal "L4GND")
		(10 "In4.Cu" signal "L5")
		(12 "In5.Cu" signal "L6GND")
		(14 "In6.Cu" signal "L7VCC")
		(16 "In7.Cu" signal "L8VCC")
		(18 "In8.Cu" signal "L9GND")
		(20 "In9.Cu" signal "L10")
		(22 "In10.Cu" signal "L11GND")
		(24 "In11.Cu" signal "L12")
		(26 "In12.Cu" signal "L13GND")
		(2 "B.Cu" signal "BOTTOM")
		(9 "F.Adhes" user "F.Adhesive")
		(11 "B.Adhes" user "B.Adhesive")
		(13 "F.Paste" user "Package Geometry/Pastemask Top")
		(15 "B.Paste" user "Package Geometry/Pastemask Bottom")
		(5 "F.SilkS" user "Ref Des/Silkscreen Top")
		(7 "B.SilkS" user "Ref Des/Silkscreen Bottom")
		(1 "F.Mask" user "Board Geometry/Soldermask Top")
		(3 "B.Mask" user "Board Geometry/Soldermask Bottom")
		(17 "Dwgs.User" user "User.Drawings")
		(19 "Cmts.User" user "User.Comments")
		(21 "Eco1.User" user "User.Eco1")
		(23 "Eco2.User" user "User.Eco2")
		(25 "Edge.Cuts" user "Board Geometry/Outline")
		(27 "Margin" user)
		(31 "F.CrtYd" user "Package Geometry/Place Bound Top")
		(29 "B.CrtYd" user "Package Geometry/Place Bound Bottom")
		(35 "F.Fab" user "Ref Des/Assembly Top")
		(33 "B.Fab" user "Ref Des/Assembly Bottom")
	)
	(footprint ""
		(layer "F.Cu")
		(at 443.289944 -153.225246 90)
		(property "Reference" "FB25W1"
			(at 0 0 90)
			(layer "F.SilkS")
			(hide yes)
			(effects
				(font
					(size 1.27 1.27)
				)
			)
		)
		(property "Value" "*"
			(at -0.0127 -7.01675 90)
			(unlocked yes)
			(layer "F.Fab")
			(hide yes)
			(effects
				(font
					(size 0.889 0.889)
					(thickness 0.1524)
				)
			)
		)
		(property "Device Type" "BLM15AG121SN-1GP_DISCRET-G-BLMA"
			(at -0.0127 -8.54075 90)
			(unlocked yes)
			(layer "F.Fab")
			(hide yes)
			(effects
				(font
					(size 0.889 0.889)
					(thickness 0.1524)
				)
			)
		)
		(duplicate_pad_numbers_are_jumpers no)
		(fp_line
			(start 0.508 -0.9398)
			(end -0.508 -0.9398)
			(stroke
				(width 0.1524)
				(type default)
			)
			(layer "F.SilkS")
		)
		(fp_line
			(start -0.508 -0.9398)
			(end -0.508 0.9398)
			(stroke
				(width 0.1524)
				(type default)
			)
			(layer "F.SilkS")
		)
		(fp_line
			(start -0.508 0.9398)
			(end -0.508 0.8636)
			(stroke
				(width 0.1524)
				(type default)
			)
			(layer "F.SilkS")
		)
		(fp_rect
			(start -0.508 0.9398)
			(end 0.508 -0.9398)
			(stroke
				(width 0)
				(type default)
			)
			(fill no)
			(layer "F.CrtYd")
		)
		(fp_rect
			(start -0.508 0.9398)
			(end 0.508 -0.9398)
			(stroke
				(width 0)
				(type default)
			)
			(fill no)
			(layer "F.Fab")
		)
		(pad "1" smd custom
			(at 0 -0.4445 90)
			(size 0.1397 0.1397)
			(layers "F.Cu" "F.Mask" "F.Paste")
			(net "XDP_CPU_TCK0_R")
			(options
				(clearance outline)
				(anchor circle)
			)
			(primitives
				(gr_poly
					(pts
						(arc
							(start -0.1778 -0.2794)
							(mid -0.249642 -0.249642)
							(end -0.2794 -0.1778)
						)
						(arc
							(start -0.2794 0.1778)
							(mid -0.249642 0.249642)
							(end -0.1778 0.2794)
						)
						(arc
							(start 0.1778 0.2794)
							(mid 0.249642 0.249642)
							(end 0.2794 0.1778)
						)
						(arc
							(start 0.2794 -0.1778)
							(mid 0.249642 -0.249642)
							(end 0.1778 -0.2794)
						)
					)
					(width 0)
					(fill yes)
				)
			)
		)
		(pad "2" smd custom
			(at 0 0.4445 90)
			(size 0.1397 0.1397)
			(layers "F.Cu" "F.Mask" "F.Paste")
			(net "XDP_CPU_TCK0")
			(options
				(clearance outline)
				(anchor circle)
			)
			(primitives
				(gr_poly
					(pts
						(arc
							(start -0.1778 -0.2794)
							(mid -0.249642 -0.249642)
							(end -0.2794 -0.1778)
						)
						(arc
							(start -0.2794 0.1778)
							(mid -0.249642 0.249642)
							(end -0.1778 0.2794)
						)
						(arc
							(start 0.1778 0.2794)
							(mid 0.249642 0.249642)
							(end 0.2794 0.1778)
						)
						(arc
							(start 0.2794 -0.1778)
							(mid 0.249642 -0.249642)
							(end 0.1778 -0.2794)
						)
					)
					(width 0)
					(fill yes)
				)
			)
		)
	)
	(footprint ""
		(layer "F.Cu")
		(at 379.5522 -158.0896)
		(property "Reference" "C7A43"
			(at 0 0 0)
			(layer "F.SilkS")
			(hide yes)
			(effects
				(font
					(size 1.27 1.27)
				)
			)
		)
		(property "Value" ""
			(at 0 0 0)
			(layer "F.Fab")
			(effects
				(font
					(size 1.27 1.27)
				)
			)
		)
		(duplicate_pad_numbers_are_jumpers no)
		(fp_poly
			(pts
				(xy 0.3048 -0.1016) (xy 0.3048 0.9906) (xy -0.3048 0.9906) (xy -0.3048 -0.1016)
			)
			(stroke
				(width 0)
				(type default)
			)
			(fill no)
			(layer "F.CrtYd")
		)
		(fp_line
			(start -0.3048 -0.1016)
			(end -0.3048 0.9906)
			(stroke
				(width 0.1)
				(type default)
			)
			(layer "F.Fab")
		)
		(fp_line
			(start -0.3048 0.9906)
			(end 0.3048 0.9906)
			(stroke
				(width 0.1)
				(type default)
			)
			(layer "F.Fab")
		)
		(fp_line
			(start 0.3048 -0.1016)
			(end -0.3048 -0.1016)
			(stroke
				(width 0.1)
				(type default)
			)
			(layer "F.Fab")
		)
		(fp_line
			(start 0.3048 0.9906)
			(end 0.3048 -0.1016)
			(stroke
				(width 0.1)
				(type default)
			)
			(layer "F.Fab")
		)
		(pad "1" smd rect
			(at 0 0)
			(size 0.508 0.508)
			(layers "F.Cu" "F.Mask" "F.Paste")
			(net "VR_PVNN_PCH_PH1_BOOT")
		)
		(pad "2" smd rect
			(at 0 0.889)
			(size 0.508 0.508)
			(layers "F.Cu" "F.Mask" "F.Paste")
			(net "VR_PVNN_PCH_PH1_PHASE")
		)
		(zone
			(layer "F.Cu")
			(hatch none 0.5)
			(connect_pads
				(clearance 0)
			)
			(min_thickness 0.25)
			(keepout
				(tracks allowed)
				(vias not_allowed)
				(pads allowed)
				(copperpour not_allowed)
				(footprints allowed)
			)
			(placement
				(enabled no)
				(sheetname "")
			)
			(fill
				(thermal_gap 0.5)
				(thermal_bridge_width 0.5)
				(island_removal_mode 0)
			)
			(polygon
				(pts
					(xy 379.2982 -157.8356) (xy 379.8062 -157.8356) (xy 379.8062 -157.4546) (xy 379.2982 -157.4546)
				)
			)
		)
		(zone
			(layer "F.Cu")
			(hatch none 0.5)
			(connect_pads
				(clearance 0)
			)
			(min_thickness 0.25)
			(keepout
				(tracks not_allowed)
				(vias allowed)
				(pads allowed)
				(copperpour not_allowed)
				(footprints allowed)
			)
			(placement
				(enabled no)
				(sheetname "")
			)
			(fill
				(thermal_gap 0.5)
				(thermal_bridge_width 0.5)
				(island_removal_mode 0)
			)
			(polygon
				(pts
					(xy 379.2982 -157.4546) (xy 379.8062 -157.4546) (xy 379.8062 -157.8356) (xy 379.2982 -157.8356)
				)
			)
		)
	)
	(footprint ""
		(layer "F.Cu")
		(at 107.8611 -3.3528 90)
		(property "Reference" "C3G5"
			(at 1.848866 0.752348 90)
			(unlocked yes)
			(layer "F.SilkS")
			(effects
				(font
					(size 1.27 0.9652)
					(thickness 0.1524)
				)
			)
		)
		(property "Value" ""
			(at 0 0 90)
			(layer "F.Fab")
			(effects
				(font
					(size 1.27 1.27)
				)
			)
		)
		(duplicate_pad_numbers_are_jumpers no)
		(fp_rect
			(start -0.500126 1.598422)
			(end 0.500126 -0.201422)
			(stroke
				(width 0)
				(type default)
			)
			(fill no)
			(layer "F.CrtYd")
		)
		(fp_line
			(start 0.500126 -0.201422)
			(end 0.500126 1.598422)
			(stroke
				(width 0.1)
				(type default)
			)
			(layer "F.Fab")
		)
		(fp_line
			(start -0.500126 -0.201422)
			(end 0.500126 -0.201422)
			(stroke
				(width 0.1)
				(type default)
			)
			(layer "F.Fab")
		)
		(fp_line
			(start 0.500126 1.598422)
			(end -0.500126 1.598422)
			(stroke
				(width 0.1)
				(type default)
			)
			(layer "F.Fab")
		)
		(fp_line
			(start -0.500126 1.598422)
			(end -0.500126 -0.201422)
			(stroke
				(width 0.1)
				(type default)
			)
			(layer "F.Fab")
		)
		(pad "1" smd rect
			(at 0 0)
			(size 0.889 0.9906)
			(layers "F.Cu" "F.Mask" "F.Paste")
			(net "PVDDQ_GHJ")
		)
		(pad "2" smd rect
			(at 0 1.397)
			(size 0.889 0.9906)
			(layers "F.Cu" "F.Mask" "F.Paste")
			(net "GND")
		)
		(zone
			(layer "F.Cu")
			(hatch none 0.5)
			(connect_pads
				(clearance 0)
			)
			(min_thickness 0.25)
			(keepout
				(tracks not_allowed)
				(vias allowed)
				(pads allowed)
				(copperpour not_allowed)
				(footprints allowed)
			)
			(placement
				(enabled no)
				(sheetname "")
			)
			(fill
				(thermal_gap 0.5)
				(thermal_bridge_width 0.5)
				(island_removal_mode 0)
			)
			(polygon
				(pts
					(xy 108.8136 -2.8575) (xy 108.8136 -3.8481) (xy 108.3056 -3.8481) (xy 108.3056 -2.8575)
				)
			)
		)
		(zone
			(layer "F.Cu")
			(hatch none 0.5)
			(connect_pads
				(clearance 0)
			)
			(min_thickness 0.25)
			(keepout
				(tracks allowed)
				(vias not_allowed)
				(pads allowed)
				(copperpour not_allowed)
				(footprints allowed)
			)
			(placement
				(enabled no)
				(sheetname "")
			)
			(fill
				(thermal_gap 0.5)
				(thermal_bridge_width 0.5)
				(island_removal_mode 0)
			)
			(polygon
				(pts
					(xy 108.8136 -2.8575) (xy 108.8136 -3.8481) (xy 108.3056 -3.8481) (xy 108.3056 -2.8575)
				)
			)
		)
	)
	(footprint ""
		(layer "F.Cu")
		(at 422.2877 -104.267 -90)
		(property "Reference" "R6W27"
			(at -0.8382 -0.67818 270)
			(unlocked yes)
			(layer "F.SilkS")
			(effects
				(font
					(size 0.4064 0.254)
					(thickness 0.1524)
				)
				(justify left)
			)
		)
		(property "Value" ""
			(at 0 0 270)
			(layer "F.Fab")
			(effects
				(font
					(size 1.27 1.27)
				)
			)
		)
		(duplicate_pad_numbers_are_jumpers no)
		(fp_poly
			(pts
				(xy -0.2794 -0.1016) (xy 0.2794 -0.1016) (xy 0.2794 0.9906) (xy -0.2794 0.9906)
			)
			(stroke
				(width 0)
				(type default)
			)
			(fill no)
			(layer "F.CrtYd")
		)
		(fp_line
			(start -0.2794 0.9906)
			(end 0.2794 0.9906)
			(stroke
				(width 0.1)
				(type default)
			)
			(layer "F.Fab")
		)
		(fp_line
			(start 0.2794 0.9906)
			(end 0.2794 -0.1016)
			(stroke
				(width 0.1)
				(type default)
			)
			(layer "F.Fab")
		)
		(fp_line
			(start -0.2794 -0.1016)
			(end -0.2794 0.9906)
			(stroke
				(width 0.1)
				(type default)
			)
			(layer "F.Fab")
		)
		(fp_line
			(start 0.2794 -0.1016)
			(end -0.2794 -0.1016)
			(stroke
				(width 0.1)
				(type default)
			)
			(layer "F.Fab")
		)
		(pad "1" smd rect
			(at 0 0 270)
			(size 0.508 0.508)
			(layers "F.Cu" "F.Mask" "F.Paste")
			(net "SMB_CPU0_PE_HP_GTL_SDA")
		)
		(pad "2" smd rect
			(at 0 0.889 270)
			(size 0.508 0.508)
			(layers "F.Cu" "F.Mask" "F.Paste")
			(net "SMB_CPU0_PE_HP_GTL_R_SDA")
		)
		(zone
			(layer "F.Cu")
			(hatch none 0.5)
			(connect_pads
				(clearance 0)
			)
			(min_thickness 0.25)
			(keepout
				(tracks not_allowed)
				(vias allowed)
				(pads allowed)
				(copperpour not_allowed)
				(footprints allowed)
			)
			(placement
				(enabled no)
				(sheetname "")
			)
			(fill
				(thermal_gap 0.5)
				(thermal_bridge_width 0.5)
				(island_removal_mode 0)
			)
			(polygon
				(pts
					(xy 421.6527 -104.521) (xy 421.6527 -104.013) (xy 422.0337 -104.013) (xy 422.0337 -104.521)
				)
			)
		)
		(zone
			(layer "F.Cu")
			(hatch none 0.5)
			(connect_pads
				(clearance 0)
			)
			(min_thickness 0.25)
			(keepout
				(tracks allowed)
				(vias not_allowed)
				(pads allowed)
				(copperpour not_allowed)
				(footprints allowed)
			)
			(placement
				(enabled no)
				(sheetname "")
			)
			(fill
				(thermal_gap 0.5)
				(thermal_bridge_width 0.5)
				(island_removal_mode 0)
			)
			(polygon
				(pts
					(xy 422.0337 -104.521) (xy 422.0337 -104.013) (xy 421.6527 -104.013) (xy 421.6527 -104.521)
				)
			)
		)
	)
	(footprint ""
		(layer "F.Cu")
		(at 99.453192 -69.885814 -90)
		(property "Reference" "C2D41"
			(at 0 0 270)
			(layer "F.SilkS")
			(hide yes)
			(effects
				(font
					(size 1.27 1.27)
				)
			)
		)
		(property "Value" ""
			(at 0 0 270)
			(layer "F.Fab")
			(effects
				(font
					(size 1.27 1.27)
				)
			)
		)
		(duplicate_pad_numbers_are_jumpers no)
		(fp_poly
			(pts
				(xy -0.4953 -0.2032) (xy 0.4953 -0.2032) (xy 0.4953 1.6002) (xy -0.4953 1.6002)
			)
			(stroke
				(width 0)
				(type default)
			)
			(fill no)
			(layer "F.CrtYd")
		)
		(fp_line
			(start -0.4953 1.6002)
			(end -0.4953 -0.2032)
			(stroke
				(width 0.1)
				(type default)
			)
			(layer "F.Fab")
		)
		(fp_line
			(start 0.4953 1.6002)
			(end -0.4953 1.6002)
			(stroke
				(width 0.1)
				(type default)
			)
			(layer "F.Fab")
		)
		(fp_line
			(start -0.4953 -0.2032)
			(end 0.4953 -0.2032)
			(stroke
				(width 0.1)
				(type default)
			)
			(layer "F.Fab")
		)
		(fp_line
			(start 0.4953 -0.2032)
			(end 0.4953 1.6002)
			(stroke
				(width 0.1)
				(type default)
			)
			(layer "F.Fab")
		)
		(pad "1" smd rect
			(at 0 0 270)
			(size 0.762 0.889)
			(layers "F.Cu" "F.Mask" "F.Paste")
			(net "PVDDQ_GHJ")
		)
		(pad "2" smd rect
			(at 0 1.397 270)
			(size 0.762 0.889)
			(layers "F.Cu" "F.Mask" "F.Paste")
			(net "GND")
		)
		(zone
			(layer "F.Cu")
			(hatch none 0.5)
			(connect_pads
				(clearance 0)
			)
			(min_thickness 0.25)
			(keepout
				(tracks not_allowed)
				(vias allowed)
				(pads allowed)
				(copperpour not_allowed)
				(footprints allowed)
			)
			(placement
				(enabled no)
				(sheetname "")
			)
			(fill
				(thermal_gap 0.5)
				(thermal_bridge_width 0.5)
				(island_removal_mode 0)
			)
			(polygon
				(pts
					(xy 99.008692 -70.266814) (xy 99.008692 -69.504814) (xy 98.500692 -69.504814) (xy 98.500692 -70.266814)
				)
			)
		)
	)
	(footprint ""
		(layer "F.Cu")
		(at 155.0416 -130.3528 90)
		(property "Reference" "C3B2"
			(at 0 0 90)
			(layer "F.SilkS")
			(hide yes)
			(effects
				(font
					(size 1.27 1.27)
				)
			)
		)
		(property "Value" ""
			(at 0 0 90)
			(layer "F.Fab")
			(effects
				(font
					(size 1.27 1.27)
				)
			)
		)
		(duplicate_pad_numbers_are_jumpers no)
		(fp_rect
			(start -0.4953 1.6002)
			(end 0.4953 -0.2032)
			(stroke
				(width 0)
				(type default)
			)
			(fill no)
			(layer "F.CrtYd")
		)
		(fp_line
			(start 0.4953 -0.2032)
			(end 0.4953 1.6002)
			(stroke
				(width 0.1)
				(type default)
			)
			(layer "F.Fab")
		)
		(fp_line
			(start -0.4953 -0.2032)
			(end 0.4953 -0.2032)
			(stroke
				(width 0.1)
				(type default)
			)
			(layer "F.Fab")
		)
		(fp_line
			(start 0.4953 1.6002)
			(end -0.4953 1.6002)
			(stroke
				(width 0.1)
				(type default)
			)
			(layer "F.Fab")
		)
		(fp_line
			(start -0.4953 1.6002)
			(end -0.4953 -0.2032)
			(stroke
				(width 0.1)
				(type default)
			)
			(layer "F.Fab")
		)
		(pad "1" smd rect
			(at 0 0 90)
			(size 0.762 0.889)
			(layers "F.Cu" "F.Mask" "F.Paste")
			(net "PVPP_KLM")
		)
		(pad "2" smd rect
			(at 0 1.397 90)
			(size 0.762 0.889)
			(layers "F.Cu" "F.Mask" "F.Paste")
			(net "GND")
		)
		(zone
			(layer "F.Cu")
			(hatch none 0.5)
			(connect_pads
				(clearance 0)
			)
			(min_thickness 0.25)
			(keepout
				(tracks not_allowed)
				(vias allowed)
				(pads allowed)
				(copperpour not_allowed)
				(footprints allowed)
			)
			(placement
				(enabled no)
				(sheetname "")
			)
			(fill
				(thermal_gap 0.5)
				(thermal_bridge_width 0.5)
				(island_removal_mode 0)
			)
			(polygon
				(pts
					(xy 155.9941 -129.9718) (xy 155.9941 -130.7338) (xy 155.4861 -130.7338) (xy 155.4861 -129.9718)
				)
			)
		)
	)
	(footprint ""
		(layer "F.Cu")
		(at 14.529816 -2.086864 -90)
		(property "Reference" "R1G16"
			(at 0 0 270)
			(layer "F.SilkS")
			(hide yes)
			(effects
				(font
					(size 1.27 1.27)
				)
			)
		)
		(property "Value" ""
			(at 0 0 270)
			(layer "F.Fab")
			(effects
				(font
					(size 1.27 1.27)
				)
			)
		)
		(duplicate_pad_numbers_are_jumpers no)
		(fp_rect
			(start -0.2794 0.9906)
			(end 0.2794 -0.1016)
			(stroke
				(width 0)
				(type default)
			)
			(fill no)
			(layer "F.CrtYd")
		)
		(fp_line
			(start -0.2794 0.9906)
			(end 0.2794 0.9906)
			(stroke
				(width 0.1)
				(type default)
			)
			(layer "F.Fab")
		)
		(fp_line
			(start 0.2794 0.9906)
			(end 0.2794 -0.1016)
			(stroke
				(width 0.1)
				(type default)
			)
			(layer "F.Fab")
		)
		(fp_line
			(start -0.2794 -0.1016)
			(end -0.2794 0.9906)
			(stroke
				(width 0.1)
				(type default)
			)
			(layer "F.Fab")
		)
		(fp_line
			(start 0.2794 -0.1016)
			(end -0.2794 -0.1016)
			(stroke
				(width 0.1)
				(type default)
			)
			(layer "F.Fab")
		)
		(pad "1" smd rect
			(at 0 0 270)
			(size 0.508 0.508)
			(layers "F.Cu" "F.Mask" "F.Paste")
			(net "P3V3_STBY")
		)
		(pad "2" smd rect
			(at 0 0.889 270)
			(size 0.508 0.508)
			(layers "F.Cu" "F.Mask" "F.Paste")
			(net "PWRGD_PVDDQ_GHJ_R")
		)
		(zone
			(layer "F.Cu")
			(hatch none 0.5)
			(connect_pads
				(clearance 0)
			)
			(min_thickness 0.25)
			(keepout
				(tracks allowed)
				(vias not_allowed)
				(pads allowed)
				(copperpour not_allowed)
				(footprints allowed)
			)
			(placement
				(enabled no)
				(sheetname "")
			)
			(fill
				(thermal_gap 0.5)
				(thermal_bridge_width 0.5)
				(island_removal_mode 0)
			)
			(polygon
				(pts
					(xy 13.894816 -2.340864) (xy 13.894816 -1.832864) (xy 14.275816 -1.832864) (xy 14.275816 -2.340864)
				)
			)
		)
		(zone
			(layer "F.Cu")
			(hatch none 0.5)
			(connect_pads
				(clearance 0)
			)
			(min_thickness 0.25)
			(keepout
				(tracks not_allowed)
				(vias allowed)
				(pads allowed)
				(copperpour not_allowed)
				(footprints allowed)
			)
			(placement
				(enabled no)
				(sheetname "")
			)
			(fill
				(thermal_gap 0.5)
				(thermal_bridge_width 0.5)
				(island_removal_mode 0)
			)
			(polygon
				(pts
					(xy 13.894816 -2.340864) (xy 13.894816 -1.832864) (xy 14.275816 -1.832864) (xy 14.275816 -2.340864)
				)
			)
		)
	)
	(footprint ""
		(layer "F.Cu")
		(at 396.494 -66.1416 -90)
		(property "Reference" "R8E33"
			(at 0 0 270)
			(layer "F.SilkS")
			(hide yes)
			(effects
				(font
					(size 1.27 1.27)
				)
			)
		)
		(property "Value" ""
			(at 0 0 270)
			(layer "F.Fab")
			(effects
				(font
					(size 1.27 1.27)
				)
			)
		)
		(duplicate_pad_numbers_are_jumpers no)
		(fp_poly
			(pts
				(xy -0.2794 -0.1016) (xy 0.2794 -0.1016) (xy 0.2794 0.9906) (xy -0.2794 0.9906)
			)
			(stroke
				(width 0)
				(type default)
			)
			(fill no)
			(layer "F.CrtYd")
		)
		(fp_line
			(start -0.2794 0.9906)
			(end 0.2794 0.9906)
			(stroke
				(width 0.1)
				(type default)
			)
			(layer "F.Fab")
		)
		(fp_line
			(start 0.2794 0.9906)
			(end 0.2794 -0.1016)
			(stroke
				(width 0.1)
				(type default)
			)
			(layer "F.Fab")
		)
		(fp_line
			(start -0.2794 -0.1016)
			(end -0.2794 0.9906)
			(stroke
				(width 0.1)
				(type default)
			)
			(layer "F.Fab")
		)
		(fp_line
			(start 0.2794 -0.1016)
			(end -0.2794 -0.1016)
			(stroke
				(width 0.1)
				(type default)
			)
			(layer "F.Fab")
		)
		(pad "1" smd rect
			(at 0 0 270)
			(size 0.508 0.508)
			(layers "F.Cu" "F.Mask" "F.Paste")
			(net "PWRGD_P12V_HSC_DLY")
		)
		(pad "2" smd rect
			(at 0 0.889 270)
			(size 0.508 0.508)
			(layers "F.Cu" "F.Mask" "F.Paste")
			(net "VR_P5V_STBY_EN")
		)
		(zone
			(layer "F.Cu")
			(hatch none 0.5)
			(connect_pads
				(clearance 0)
			)
			(min_thickness 0.25)
			(keepout
				(tracks not_allowed)
				(vias allowed)
				(pads allowed)
				(copperpour not_allowed)
				(footprints allowed)
			)
			(placement
				(enabled no)
				(sheetname "")
			)
			(fill
				(thermal_gap 0.5)
				(thermal_bridge_width 0.5)
				(island_removal_mode 0)
			)
			(polygon
				(pts
					(xy 395.859 -66.3956) (xy 395.859 -65.8876) (xy 396.24 -65.8876) (xy 396.24 -66.3956)
				)
			)
		)
		(zone
			(layer "F.Cu")
			(hatch none 0.5)
			(connect_pads
				(clearance 0)
			)
			(min_thickness 0.25)
			(keepout
				(tracks allowed)
				(vias not_allowed)
				(pads allowed)
				(copperpour not_allowed)
				(footprints allowed)
			)
			(placement
				(enabled no)
				(sheetname "")
			)
			(fill
				(thermal_gap 0.5)
				(thermal_bridge_width 0.5)
				(island_removal_mode 0)
			)
			(polygon
				(pts
					(xy 396.24 -66.3956) (xy 396.24 -65.8876) (xy 395.859 -65.8876) (xy 395.859 -66.3956)
				)
			)
		)
	)
)
